# T6G (Grand Teton) — schematic netlist excerpt (pin names and nets, part order shuffled) for the footprints in the layout excerpt that follows; sources: Cadence DE-HDL packaged netlist, KiCad conversion of 04192023_DAF0TMB3IC0_F0TG_MB_C_brd_V02_OCP.brd

C1513  Q_CAP  0.1UF 16V 10% X7R  pkg C0402  page 173 : A = PVDD18_S5_P0 ; B = GND
PC405_4  Q_CAP  0.1UF 25V 10% X7R  pkg 0402  page 219 : A = SW_P12V_AUX_PVDDCR_CPU1_P1_FLT ; B = GND

(kicad_pcb
	(version 20260206)
	(generator "pcbnew")
	(generator_version "10.0")
	(general
		(thickness 1.6)
		(legacy_teardrops no)
	)
	(paper "A4")
	(title_block
		(title "04192023_DAF0TMB3IC0_F0TG_MB_C_brd_V02_OCP.brd")
		(comment 1 "Grand Teton / footprints 2024-2025 of 8354")
	)
	(layers
		(0 "F.Cu" signal "TOP")
		(4 "In1.Cu" signal "GND")
		(6 "In2.Cu" signal "IN1")
		(8 "In3.Cu" signal "GND1")
		(10 "In4.Cu" signal "IN2")
		(12 "In5.Cu" signal "GND2")
		(14 "In6.Cu" signal "IN3")
		(16 "In7.Cu" signal "GND3")
		(18 "In8.Cu" signal "VCC")
		(20 "In9.Cu" signal "VCC1")
		(22 "In10.Cu" signal "GND4")
		(24 "In11.Cu" signal "IN4")
		(26 "In12.Cu" signal "GND5")
		(28 "In13.Cu" signal "IN5")
		(30 "In14.Cu" signal "GND6")
		(32 "In15.Cu" signal "IN6")
		(34 "In16.Cu" signal "GND7")
		(2 "B.Cu" signal "BOTTOM")
		(9 "F.Adhes" user "F.Adhesive")
		(11 "B.Adhes" user "B.Adhesive")
		(13 "F.Paste" user "Package Geometry/Pastemask Top")
		(15 "B.Paste" user "Package Geometry/Pastemask Bottom")
		(5 "F.SilkS" user "Ref Des/Silkscreen Top")
		(7 "B.SilkS" user "Ref Des/Silkscreen Bottom")
		(1 "F.Mask" user "Board Geometry/Soldermask Top")
		(3 "B.Mask" user "Board Geometry/Soldermask Bottom")
		(17 "Dwgs.User" user "User.Drawings")
		(19 "Cmts.User" user "User.Comments")
		(21 "Eco1.User" user "User.Eco1")
		(23 "Eco2.User" user "User.Eco2")
		(25 "Edge.Cuts" user "Board Geometry/Outline")
		(27 "Margin" user)
		(31 "F.CrtYd" user "Package Geometry/Place Bound Top")
		(29 "B.CrtYd" user "Package Geometry/Place Bound Bottom")
		(35 "F.Fab" user "Ref Des/Assembly Top")
		(33 "B.Fab" user "Ref Des/Assembly Bottom")
	)
	(footprint ""
		(layer "F.Cu")
		(at 66.491612 -346.86875 -90)
		(property "Reference" "PC405_4"
			(at 0 0 270)
			(layer "F.SilkS")
			(hide yes)
			(effects
				(font
					(size 1.27 1.27)
				)
			)
		)
		(property "Value" ""
			(at 0 0 270)
			(layer "F.Fab")
			(effects
				(font
					(size 1.27 1.27)
				)
			)
		)
		(duplicate_pad_numbers_are_jumpers no)
		(fp_line
			(start -0.7874 0.4064)
			(end -0.7874 -0.4064)
			(stroke
				(width 0.1524)
				(type default)
			)
			(layer "F.SilkS")
		)
		(fp_line
			(start 0.7874 0.4064)
			(end -0.7874 0.4064)
			(stroke
				(width 0.1524)
				(type default)
			)
			(layer "F.SilkS")
		)
		(fp_line
			(start -0.7874 -0.4064)
			(end 0.7874 -0.4064)
			(stroke
				(width 0.1524)
				(type default)
			)
			(layer "F.SilkS")
		)
		(fp_line
			(start 0.7874 -0.4064)
			(end 0.7874 0.4064)
			(stroke
				(width 0.1524)
				(type default)
			)
			(layer "F.SilkS")
		)
		(fp_line
			(start -0.67945 0.3048)
			(end -0.67945 -0.305054)
			(stroke
				(width 0.1)
				(type default)
			)
			(layer "F.Fab")
		)
		(fp_line
			(start -0.12065 0.3048)
			(end -0.67945 0.3048)
			(stroke
				(width 0.1)
				(type default)
			)
			(layer "F.Fab")
		)
		(fp_line
			(start 0.120396 0.3048)
			(end 0.120396 0.2794)
			(stroke
				(width 0.1)
				(type default)
			)
			(layer "F.Fab")
		)
		(fp_line
			(start 0.67945 0.3048)
			(end 0.120396 0.3048)
			(stroke
				(width 0.1)
				(type default)
			)
			(layer "F.Fab")
		)
		(fp_line
			(start -0.12065 0.2794)
			(end -0.12065 0.3048)
			(stroke
				(width 0.1)
				(type default)
			)
			(layer "F.Fab")
		)
		(fp_line
			(start 0.120396 0.2794)
			(end -0.12065 0.2794)
			(stroke
				(width 0.1)
				(type default)
			)
			(layer "F.Fab")
		)
		(fp_line
			(start -0.12065 -0.2794)
			(end 0.12065 -0.2794)
			(stroke
				(width 0.1)
				(type default)
			)
			(layer "F.Fab")
		)
		(fp_line
			(start 0.12065 -0.2794)
			(end 0.12065 -0.3048)
			(stroke
				(width 0.1)
				(type default)
			)
			(layer "F.Fab")
		)
		(fp_line
			(start 0.12065 -0.3048)
			(end 0.67945 -0.3048)
			(stroke
				(width 0.1)
				(type default)
			)
			(layer "F.Fab")
		)
		(fp_line
			(start 0.67945 -0.3048)
			(end 0.67945 0.3048)
			(stroke
				(width 0.1)
				(type default)
			)
			(layer "F.Fab")
		)
		(fp_line
			(start -0.67945 -0.305054)
			(end -0.12065 -0.305054)
			(stroke
				(width 0.1)
				(type default)
			)
			(layer "F.Fab")
		)
		(fp_line
			(start -0.12065 -0.305054)
			(end -0.12065 -0.2794)
			(stroke
				(width 0.1)
				(type default)
			)
			(layer "F.Fab")
		)
		(pad "1" smd circle
			(at -0.40005 0 270)
			(size 0 0)
			(layers "F.Cu" "F.Mask" "F.Paste")
			(net "SW_P12V_AUX_PVDDCR_CPU1_P1_FLT")
		)
		(pad "2" smd circle
			(at 0.40005 0 270)
			(size 0 0)
			(layers "F.Cu" "F.Mask" "F.Paste")
			(net "GND")
		)
	)
	(footprint ""
		(layer "F.Cu")
		(at 132.610352 -52.28844 90)
		(property "Reference" "C1513"
			(at 0 0 90)
			(layer "F.SilkS")
			(hide yes)
			(effects
				(font
					(size 1.27 1.27)
				)
			)
		)
		(property "Value" ""
			(at 0 0 90)
			(layer "F.Fab")
			(effects
				(font
					(size 1.27 1.27)
				)
			)
		)
		(duplicate_pad_numbers_are_jumpers no)
		(fp_line
			(start 0.7874 -0.4064)
			(end 0.7874 0.4064)
			(stroke
				(width 0.1524)
				(type default)
			)
			(layer "F.SilkS")
		)
		(fp_line
			(start -0.7874 -0.4064)
			(end 0.7874 -0.4064)
			(stroke
				(width 0.1524)
				(type default)
			)
			(layer "F.SilkS")
		)
		(fp_line
			(start 0.7874 0.4064)
			(end -0.7874 0.4064)
			(stroke
				(width 0.1524)
				(type default)
			)
			(layer "F.SilkS")
		)
		(fp_line
			(start -0.7874 0.4064)
			(end -0.7874 -0.4064)
			(stroke
				(width 0.1524)
				(type default)
			)
			(layer "F.SilkS")
		)
		(fp_line
			(start -0.12065 -0.305054)
			(end -0.12065 -0.2794)
			(stroke
				(width 0.1)
				(type default)
			)
			(layer "F.Fab")
		)
		(fp_line
			(start -0.67945 -0.305054)
			(end -0.12065 -0.305054)
			(stroke
				(width 0.1)
				(type default)
			)
			(layer "F.Fab")
		)
		(fp_line
			(start 0.67945 -0.3048)
			(end 0.67945 0.3048)
			(stroke
				(width 0.1)
				(type default)
			)
			(layer "F.Fab")
		)
		(fp_line
			(start 0.12065 -0.3048)
			(end 0.67945 -0.3048)
			(stroke
				(width 0.1)
				(type default)
			)
			(layer "F.Fab")
		)
		(fp_line
			(start 0.12065 -0.2794)
			(end 0.12065 -0.3048)
			(stroke
				(width 0.1)
				(type default)
			)
			(layer "F.Fab")
		)
		(fp_line
			(start -0.12065 -0.2794)
			(end 0.12065 -0.2794)
			(stroke
				(width 0.1)
				(type default)
			)
			(layer "F.Fab")
		)
		(fp_line
			(start 0.120396 0.2794)
			(end -0.12065 0.2794)
			(stroke
				(width 0.1)
				(type default)
			)
			(layer "F.Fab")
		)
		(fp_line
			(start -0.12065 0.2794)
			(end -0.12065 0.3048)
			(stroke
				(width 0.1)
				(type default)
			)
			(layer "F.Fab")
		)
		(fp_line
			(start 0.67945 0.3048)
			(end 0.120396 0.3048)
			(stroke
				(width 0.1)
				(type default)
			)
			(layer "F.Fab")
		)
		(fp_line
			(start 0.120396 0.3048)
			(end 0.120396 0.2794)
			(stroke
				(width 0.1)
				(type default)
			)
			(layer "F.Fab")
		)
		(fp_line
			(start -0.12065 0.3048)
			(end -0.67945 0.3048)
			(stroke
				(width 0.1)
				(type default)
			)
			(layer "F.Fab")
		)
		(fp_line
			(start -0.67945 0.3048)
			(end -0.67945 -0.305054)
			(stroke
				(width 0.1)
				(type default)
			)
			(layer "F.Fab")
		)
		(pad "1" smd circle
			(at -0.40005 0 90)
			(size 0 0)
			(layers "F.Cu" "F.Mask" "F.Paste")
			(net "PVDD18_S5_P0")
		)
		(pad "2" smd circle
			(at 0.40005 0 90)
			(size 0 0)
			(layers "F.Cu" "F.Mask" "F.Paste")
			(net "GND")
		)
	)
)
